G04 ================== begin FILE IDENTIFICATION RECORD ==================*
G04 Layout Name:  D:/<user>/Wistron_project/16369-sd/gbr/16369-sd.brd*
G04 Film Name:    L2GND*
G04 File Format:  Gerber RS274X*
G04 File Origin:  Cadence Allegro 16.5-S056*
G04 Origin Date:  Wed Mar 29 13:12:53 2017*
G04 *
G04 Layer:  VIA CLASS/L2GND*
G04 Layer:  PIN/L2GND*
G04 Layer:  ETCH/L2GND*
G04 Layer:  DRAWING FORMAT/LAYER_PCB_STORY*
G04 Layer:  DRAWING FORMAT/LAYER_L2GND*
G04 *
G04 Offset:    (0.00 0.00)*
G04 Mirror:    No*
G04 Mode:      Negative*
G04 Rotation:  0*
G04 FullContactRelief:  No*
G04 UndefLineWidth:     6.00*
G04 ================== end FILE IDENTIFICATION RECORD ====================*
%FSLAX35Y35*MOIN*%
%IR0*IPPOS*OFA0.00000B0.00000*MIA0B0*SFA1.00000B1.00000*%
%ADD13C,.03*%
%ADD20C,.032*%
%ADD15C,.06*%
%ADD12C,.08*%
%ADD21C,.036*%
%ADD22C,.064*%
%ADD16C,.056*%
%AMMACRO25*
4,1,15,.00398,.00044,
.003999,.000208,
.004004,-.000025,
.003996,-.000258,
.00398,-.00044,
.00483,-.00129,
.004897,-.001007,
.004947,-.000721,
.004981,-.000432,
.004997,-.000141,
.004997,.000149,
.00498,.00044,
.004946,.000729,
.004895,.001015,
.00483,.00129,
.00398,.00044,
90.*
4,1,15,.00044,-.00398,
.000208,-.003999,
-.000025,-.004004,
-.000258,-.003996,
-.00044,-.00398,
-.00129,-.00483,
-.001007,-.004897,
-.000721,-.004947,
-.000432,-.004981,
-.000141,-.004997,
.000149,-.004997,
.00044,-.00498,
.000729,-.004946,
.001015,-.004895,
.00129,-.00483,
.00044,-.00398,
90.*
4,1,15,-.00398,-.00044,
-.003999,-.000208,
-.004004,.000025,
-.003996,.000258,
-.00398,.00044,
-.00483,.00129,
-.004897,.001007,
-.004947,.000721,
-.004981,.000432,
-.004997,.000141,
-.004997,-.000149,
-.00498,-.00044,
-.004946,-.000729,
-.004895,-.001015,
-.00483,-.00129,
-.00398,-.00044,
90.*
4,1,15,-.00044,.00398,
-.000208,.003999,
.000025,.004004,
.000258,.003996,
.00044,.00398,
.00129,.00483,
.001007,.004897,
.000721,.004947,
.000432,.004981,
.000141,.004997,
-.000149,.004997,
-.00044,.00498,
-.000729,.004946,
-.001015,.004895,
-.00129,.00483,
-.00044,.00398,
90.*
%
%ADD25MACRO25*%
%AMMACRO11*
4,1,15,.00398,.00044,
.003999,.000208,
.004004,-.000025,
.003996,-.000258,
.00398,-.00044,
.00483,-.00129,
.004897,-.001007,
.004947,-.000721,
.004981,-.000432,
.004997,-.000141,
.004997,.000149,
.00498,.00044,
.004946,.000729,
.004895,.001015,
.00483,.00129,
.00398,.00044,
0.0*
4,1,15,.00044,-.00398,
.000208,-.003999,
-.000025,-.004004,
-.000258,-.003996,
-.00044,-.00398,
-.00129,-.00483,
-.001007,-.004897,
-.000721,-.004947,
-.000432,-.004981,
-.000141,-.004997,
.000149,-.004997,
.00044,-.00498,
.000729,-.004946,
.001015,-.004895,
.00129,-.00483,
.00044,-.00398,
0.0*
4,1,15,-.00398,-.00044,
-.003999,-.000208,
-.004004,.000025,
-.003996,.000258,
-.00398,.00044,
-.00483,.00129,
-.004897,.001007,
-.004947,.000721,
-.004981,.000432,
-.004997,.000141,
-.004997,-.000149,
-.00498,-.00044,
-.004946,-.000729,
-.004895,-.001015,
-.00483,-.00129,
-.00398,-.00044,
0.0*
4,1,15,-.00044,.00398,
-.000208,.003999,
.000025,.004004,
.000258,.003996,
.00044,.00398,
.00129,.00483,
.001007,.004897,
.000721,.004947,
.000432,.004981,
.000141,.004997,
-.000149,.004997,
-.00044,.00498,
-.000729,.004946,
-.001015,.004895,
-.00129,.00483,
-.00044,.00398,
0.0*
%
%ADD11MACRO11*%
%AMMACRO26*
4,1,15,-.00398,.00044,
-.003999,.000208,
-.004004,-.000025,
-.003996,-.000258,
-.00398,-.00044,
-.00483,-.00129,
-.004897,-.001007,
-.004947,-.000721,
-.004981,-.000432,
-.004997,-.000141,
-.004997,.000149,
-.00498,.00044,
-.004946,.000729,
-.004895,.001015,
-.00483,.00129,
-.00398,.00044,
0.0*
4,1,15,-.00044,-.00398,
-.000208,-.003999,
.000025,-.004004,
.000258,-.003996,
.00044,-.00398,
.00129,-.00483,
.001007,-.004897,
.000721,-.004947,
.000432,-.004981,
.000141,-.004997,
-.000149,-.004997,
-.00044,-.00498,
-.000729,-.004946,
-.001015,-.004895,
-.00129,-.00483,
-.00044,-.00398,
0.0*
4,1,15,.00398,-.00044,
.003999,-.000208,
.004004,.000025,
.003996,.000258,
.00398,.00044,
.00483,.00129,
.004897,.001007,
.004947,.000721,
.004981,.000432,
.004997,.000141,
.004997,-.000149,
.00498,-.00044,
.004946,-.000729,
.004895,-.001015,
.00483,-.00129,
.00398,-.00044,
0.0*
4,1,15,.00044,.00398,
.000208,.003999,
-.000025,.004004,
-.000258,.003996,
-.00044,.00398,
-.00129,.00483,
-.001007,.004897,
-.000721,.004947,
-.000432,.004981,
-.000141,.004997,
.000149,.004997,
.00044,.00498,
.000729,.004946,
.001015,.004895,
.00129,.00483,
.00044,.00398,
0.0*
%
%ADD26MACRO26*%
%ADD10C,.114*%
%ADD18C,.119*%
%ADD24C,.264*%
%AMMACRO19*
4,1,15,.00398,.00044,
.003999,.000208,
.004004,-.000025,
.003996,-.000258,
.00398,-.00044,
.00483,-.00129,
.004897,-.001007,
.004947,-.000721,
.004981,-.000432,
.004997,-.000141,
.004997,.000149,
.00498,.00044,
.004946,.000729,
.004895,.001015,
.00483,.00129,
.00398,.00044,
270.*
4,1,15,.00044,-.00398,
.000208,-.003999,
-.000025,-.004004,
-.000258,-.003996,
-.00044,-.00398,
-.00129,-.00483,
-.001007,-.004897,
-.000721,-.004947,
-.000432,-.004981,
-.000141,-.004997,
.000149,-.004997,
.00044,-.00498,
.000729,-.004946,
.001015,-.004895,
.00129,-.00483,
.00044,-.00398,
270.*
4,1,15,-.00398,-.00044,
-.003999,-.000208,
-.004004,.000025,
-.003996,.000258,
-.00398,.00044,
-.00483,.00129,
-.004897,.001007,
-.004947,.000721,
-.004981,.000432,
-.004997,.000141,
-.004997,-.000149,
-.00498,-.00044,
-.004946,-.000729,
-.004895,-.001015,
-.00483,-.00129,
-.00398,-.00044,
270.*
4,1,15,-.00044,.00398,
-.000208,.003999,
.000025,.004004,
.000258,.003996,
.00044,.00398,
.00129,.00483,
.001007,.004897,
.000721,.004947,
.000432,.004981,
.000141,.004997,
-.000149,.004997,
-.00044,.00498,
-.000729,.004946,
-.001015,.004895,
-.00129,.00483,
-.00044,.00398,
270.*
%
%ADD19MACRO19*%
%AMMACRO14*
4,1,15,.00398,.00044,
.003999,.000208,
.004004,-.000025,
.003996,-.000258,
.00398,-.00044,
.00483,-.00129,
.004897,-.001007,
.004947,-.000721,
.004981,-.000432,
.004997,-.000141,
.004997,.000149,
.00498,.00044,
.004946,.000729,
.004895,.001015,
.00483,.00129,
.00398,.00044,
180.*
4,1,15,.00044,-.00398,
.000208,-.003999,
-.000025,-.004004,
-.000258,-.003996,
-.00044,-.00398,
-.00129,-.00483,
-.001007,-.004897,
-.000721,-.004947,
-.000432,-.004981,
-.000141,-.004997,
.000149,-.004997,
.00044,-.00498,
.000729,-.004946,
.001015,-.004895,
.00129,-.00483,
.00044,-.00398,
180.*
4,1,15,-.00398,-.00044,
-.003999,-.000208,
-.004004,.000025,
-.003996,.000258,
-.00398,.00044,
-.00483,.00129,
-.004897,.001007,
-.004947,.000721,
-.004981,.000432,
-.004997,.000141,
-.004997,-.000149,
-.00498,-.00044,
-.004946,-.000729,
-.004895,-.001015,
-.00483,-.00129,
-.00398,-.00044,
180.*
4,1,15,-.00044,.00398,
-.000208,.003999,
.000025,.004004,
.000258,.003996,
.00044,.00398,
.00129,.00483,
.001007,.004897,
.000721,.004947,
.000432,.004981,
.000141,.004997,
-.000149,.004997,
-.00044,.00498,
-.000729,.004946,
-.001015,.004895,
-.00129,.00483,
-.00044,.00398,
180.*
%
%ADD14MACRO14*%
%AMMACRO23*
4,1,13,.02404,.0099,
.025394,.005575,
.025976,.001081,
.025769,-.003446,
.024779,-.007869,
.02404,-.0099,
.02782,-.01368,
.029773,-.008641,
.030821,-.00334,
.030933,.002063,
.030105,.007403,
.028362,.012518,
.02782,.01368,
.02404,.0099,
0.0*
4,1,13,.0099,-.02404,
.005575,-.025394,
.001081,-.025976,
-.003446,-.025769,
-.007869,-.024779,
-.0099,-.02404,
-.01368,-.02782,
-.008641,-.029773,
-.00334,-.030821,
.002063,-.030933,
.007403,-.030105,
.012518,-.028362,
.01368,-.02782,
.0099,-.02404,
0.0*
4,1,13,-.02404,-.0099,
-.025394,-.005575,
-.025976,-.001081,
-.025769,.003446,
-.024779,.007869,
-.02404,.0099,
-.02782,.01368,
-.029773,.008641,
-.030821,.00334,
-.030933,-.002063,
-.030105,-.007403,
-.028362,-.012518,
-.02782,-.01368,
-.02404,-.0099,
0.0*
4,1,13,-.0099,.02404,
-.005575,.025394,
-.001081,.025976,
.003446,.025769,
.007869,.024779,
.0099,.02404,
.01368,.02782,
.008641,.029773,
.00334,.030821,
-.002063,.030933,
-.007403,.030105,
-.012518,.028362,
-.01368,.02782,
-.0099,.02404,
0.0*
%
%ADD23MACRO23*%
%AMMACRO17*
4,1,19,.02172,.00757,
.022123,.006294,
.022452,.004997,
.022705,.003683,
.02288,.002357,
.022979,.001023,
.022999,-.000315,
.022942,-.001652,
.022807,-.002983,
.022595,-.004304,
.022307,-.005611,
.021943,-.006898,
.02172,-.00757,
.02556,-.01142,
.027155,-.006808,
.027924,-.001989,
.027846,.00289,
.026921,.007681,
.02556,.01142,
.02172,.00757,
90.*
4,1,19,.00757,-.02172,
.006294,-.022123,
.004997,-.022452,
.003683,-.022705,
.002357,-.02288,
.001023,-.022979,
-.000315,-.022999,
-.001652,-.022942,
-.002983,-.022807,
-.004304,-.022595,
-.005611,-.022307,
-.006898,-.021943,
-.00757,-.02172,
-.01142,-.02556,
-.006808,-.027155,
-.001989,-.027924,
.00289,-.027846,
.007681,-.026921,
.01142,-.02556,
.00757,-.02172,
90.*
4,1,19,-.02172,-.00757,
-.022123,-.006294,
-.022452,-.004997,
-.022705,-.003683,
-.02288,-.002357,
-.022979,-.001023,
-.022999,.000315,
-.022942,.001652,
-.022807,.002983,
-.022595,.004304,
-.022307,.005611,
-.021943,.006898,
-.02172,.00757,
-.02556,.01142,
-.027155,.006808,
-.027924,.001989,
-.027846,-.00289,
-.026921,-.007681,
-.02556,-.01142,
-.02172,-.00757,
90.*
4,1,19,-.00757,.02172,
-.006294,.022123,
-.004997,.022452,
-.003683,.022705,
-.002357,.02288,
-.001023,.022979,
.000315,.022999,
.001652,.022942,
.002983,.022807,
.004304,.022595,
.005611,.022307,
.006898,.021943,
.00757,.02172,
.01142,.02556,
.006808,.027155,
.001989,.027924,
-.00289,.027846,
-.007681,.026921,
-.01142,.02556,
-.00757,.02172,
90.*
%
%ADD17MACRO17*%
%ADD27C,.02*%
%ADD28C,.006*%
%ADD30C,.11004*%
%ADD29C,.36204*%
G75*
%LPD*%
G75*
G36*
G01X-17811Y-32378D02*
X246551D01*
Y360331D01*
X-17811D01*
Y-32378D01*
G37*
%LPC*%
G75*
G36*
G01X61563Y137457D02*
G03X63596Y132550I6941J1D01*
G01X92786Y103360D01*
G03X97693Y101327I4908J4908D01*
G01X134984D01*
G03X139891Y103360I-1J6941D01*
G01X169081Y132550D01*
G03X171114Y137457I-4908J4908D01*
G01Y249131D01*
G03X166368Y255716I-6941J0D01*
G01X159941Y257858D01*
G02X159303Y258743I295J885D01*
G01Y276690D01*
G02X159941Y277575I933J0D01*
G01X166368Y279717D01*
G03X171114Y286302I-2195J6585D01*
G01Y350394D01*
G02X172047Y351327I933J0D01*
G01X228740D01*
G02X229673Y350394I0J-933D01*
G01Y215031D01*
G03X233511Y208823I6941J1D01*
G01X237031Y207063D01*
G02X237547Y206229I-417J-835D01*
G01Y187472D01*
G02X237031Y186638I-933J1D01*
G01X233511Y184878D01*
G03X229673Y178670I3103J-6209D01*
G01Y-22441D01*
G02X228740Y-23374I-933J0D01*
G01X204638D01*
Y-787D01*
G03X199666Y4185I-4973J-1D01*
G01X195093D01*
G02X194697Y4636I1J400D01*
G03X187155I-3771J482D01*
G02X186759Y4185I-397J-51D01*
G01X45919D01*
G02X45523Y4636I1J400D01*
G03X37981I-3771J482D01*
G02X37585Y4185I-397J-51D01*
G01X33011D01*
G03X28039Y-787I1J-4973D01*
G01Y-23374D01*
X3937D01*
G02X3004Y-22441I0J933D01*
G01Y178265D01*
G03X-1742Y184850I-6941J0D01*
G01X-8169Y186992D01*
G02X-8807Y187877I295J885D01*
G01Y205824D01*
G02X-8169Y206709I933J0D01*
G01X-1742Y208851D01*
G03X3004Y215436I-2195J6585D01*
G01Y350394D01*
G02X3937Y351327I933J0D01*
G01X60630D01*
G02X61563Y350394I0J-933D01*
G01Y286302D01*
G03X66309Y279717I6941J0D01*
G01X72736Y277575D01*
G02X73374Y276690I-295J-885D01*
G01Y258743D01*
G02X72736Y257858I-933J0D01*
G01X66309Y255716D01*
G03X61563Y249131I2195J-6585D01*
G01Y137457D01*
G37*
%LPD*%
G75*
G54D30*
X13800Y60400D03*
X218800Y337200D03*
G54D29*
X116339Y78740D03*
G54D13*
X48000Y38000D03*
X58700Y55600D03*
X73000Y57200D03*
X57400Y26400D03*
X63300Y37300D03*
X43900Y59600D03*
X42300Y51900D03*
X50100Y34500D03*
X68838Y12300D03*
X39400Y41000D03*
X36900Y17600D03*
X26000Y51600D03*
X19763Y92200D03*
X50400Y118300D03*
X24000Y120900D03*
X41492Y106258D03*
X27200Y104100D03*
X33100Y73900D03*
X32200Y91400D03*
X40000Y77100D03*
X23093Y99967D03*
X9000Y81250D03*
Y77250D03*
X40900Y88400D03*
X46200Y111200D03*
X15857Y202417D03*
X51400Y168300D03*
X16253Y180320D03*
X20539Y163381D03*
X9581Y160069D03*
X11840Y177692D03*
X99300Y25700D03*
X136439Y31761D03*
X97500Y36600D03*
X97400Y29300D03*
X132600Y29600D03*
X124300Y22600D03*
X76900Y15500D03*
X73838Y12100D03*
X126742Y15658D03*
X82200Y60800D03*
X100100Y56300D03*
X125700Y26500D03*
X79750Y76600D03*
X79604Y86869D03*
X204340Y71660D03*
X218300Y32700D03*
X222609Y53150D03*
X179093Y38185D03*
X163000Y43800D03*
X179500Y42750D03*
X178843Y59000D03*
X188250Y66000D03*
X207293Y45526D03*
X211900Y24800D03*
X194560Y56777D03*
X160800Y72000D03*
X154444Y72036D03*
X208900Y59000D03*
X160794Y86162D03*
X218700Y132335D03*
X219000Y107560D03*
X214500Y112000D03*
X192691Y84234D03*
X214800Y128309D03*
X193500Y135835D03*
X190900Y112200D03*
X159711Y82091D03*
X156891Y79378D03*
X184900Y106300D03*
X171263Y92837D03*
X224000Y210584D03*
X207750Y224016D03*
X220200Y151000D03*
X219269Y216635D03*
X209506Y229990D03*
X215916Y232222D03*
G54D20*
X51076Y202657D03*
X51500Y191500D03*
X44100Y154167D03*
X56400Y158800D03*
X55200Y285022D03*
X222800Y182000D03*
X199600Y156500D03*
X220678Y284412D03*
G54D15*
X37283Y173228D03*
X27283D03*
X193583D03*
X183583D03*
G54D12*
X41752Y5118D03*
X190926D03*
G54D21*
X16977Y244294D03*
X16984Y248748D03*
X96200Y16400D03*
X133200Y17751D03*
X107506Y16719D03*
X116430Y16569D03*
X191391Y278906D03*
X195939Y278959D03*
G54D22*
X22440Y303149D03*
X32283D03*
X22440Y322835D03*
X32283D03*
X42126D03*
X182677Y303149D03*
X192520D03*
X182677Y322835D03*
X192520D03*
X202363D03*
G54D16*
X38189Y220472D03*
Y251968D03*
Y244094D03*
Y236220D03*
Y228346D03*
X28346Y232283D03*
Y240157D03*
Y250000D03*
X12598Y312992D03*
X51968D03*
X198426Y220472D03*
Y251968D03*
Y244094D03*
Y236220D03*
Y228346D03*
X188583Y232283D03*
Y240157D03*
Y250000D03*
X172835Y312992D03*
X212205D03*
G54D25*
X79000Y43600D03*
X214119Y216661D03*
G54D11*
X6000Y-17500D03*
X16090Y-6960D03*
Y-3360D03*
X4100Y12300D03*
X4300Y38700D03*
X21000Y53500D03*
X4629Y64843D03*
X16090Y240D03*
X63938Y11580D03*
X16090Y3840D03*
X33200Y59100D03*
X35744Y51944D03*
X41000Y36900D03*
X50100Y20700D03*
X57450Y35400D03*
X55500Y42000D03*
X69446Y48262D03*
X70360Y25750D03*
X55700Y121400D03*
X70600Y122500D03*
X65600Y128100D03*
X42600Y129000D03*
X22383Y128937D03*
X20200Y116600D03*
X47300Y107940D03*
X37100Y73960D03*
X37500Y87300D03*
X17700Y89400D03*
X6220Y219509D03*
X51500Y187600D03*
X51400Y195600D03*
X56755Y199384D03*
X26700Y189160D03*
X47300Y168700D03*
X4100Y294900D03*
X60300Y290000D03*
X17100Y278300D03*
X13650Y278350D03*
X26270Y282547D03*
X5244Y259114D03*
X4333Y242011D03*
X22820Y282597D03*
X18600Y338800D03*
X4200Y312100D03*
Y329000D03*
X42800Y338500D03*
X29000Y338600D03*
X60400Y305900D03*
X60500Y316400D03*
X60300Y331800D03*
X60400Y350300D03*
X44000Y350200D03*
X20100Y350300D03*
X4400D03*
X132500Y41200D03*
X98000Y68200D03*
X112900Y51800D03*
X102000Y62400D03*
X134800Y60300D03*
X135800Y70800D03*
X140100Y14000D03*
X78838Y11602D03*
X75100Y63900D03*
X118100Y45000D03*
X104900Y21400D03*
X114900Y39900D03*
X97200Y44150D03*
X132600Y53800D03*
X119200Y30900D03*
X124300Y99500D03*
X97600Y92200D03*
X94193Y99637D03*
X81634Y111544D03*
X76100Y117800D03*
X87600Y106400D03*
X101600Y99700D03*
X135900Y99400D03*
X146700Y108400D03*
X75600Y87000D03*
Y91500D03*
X219300Y-13900D03*
X208500Y-22000D03*
X186200Y14900D03*
X222500Y35100D03*
X208500Y9400D03*
X203300Y14800D03*
X217800Y14300D03*
X168858Y12000D03*
X169750Y62500D03*
X163452Y32350D03*
X161300Y51500D03*
X174300Y52000D03*
X172800Y44950D03*
X182800Y46500D03*
X220732Y46039D03*
X194560Y53277D03*
X219000Y104060D03*
X154700Y116500D03*
X190700Y127400D03*
X211000Y140500D03*
X174600Y86980D03*
X198100Y104000D03*
X184700Y112500D03*
X218350Y111900D03*
X204818Y118400D03*
X210276Y122000D03*
X192500Y73385D03*
X186100Y186500D03*
X205848Y199637D03*
X219150Y178000D03*
X222450Y199500D03*
X218700Y193900D03*
X178747Y288699D03*
X182347Y292152D03*
X199557Y292020D03*
X214401Y281884D03*
X215411Y270499D03*
X199521Y288390D03*
X222500Y344500D03*
X200200Y343900D03*
X188300Y343400D03*
X193300Y337900D03*
X211900Y337500D03*
X219900Y330500D03*
X214200Y325100D03*
X209500Y350300D03*
X188000D03*
X172300Y337600D03*
Y350200D03*
X220550Y306050D03*
X224000Y306000D03*
X228400Y-21400D03*
X228600Y42000D03*
X228300Y6100D03*
X228400Y22800D03*
X228600Y69200D03*
Y85900D03*
X227800Y322200D03*
X228500Y337100D03*
X228400Y350200D03*
G54D26*
X217340Y-3360D03*
Y-6960D03*
Y240D03*
Y3840D03*
G54D10*
X-18898Y16741D03*
X-17506Y723144D03*
X13800Y60400D03*
X114497Y137176D03*
X115583Y329366D03*
X114497Y525759D03*
X115583Y717948D03*
X218800Y337200D03*
X365520Y-1413D03*
X366606Y190776D03*
X365520Y387169D03*
X366606Y579359D03*
X494816Y713716D03*
G54D18*
X40157Y211023D03*
X24409D03*
X40157Y261417D03*
X24409D03*
X200394Y211023D03*
X184646D03*
X200394Y261417D03*
X184646D03*
G54D24*
X116339Y78740D03*
G54D14*
X22800Y112600D03*
X32100Y114900D03*
X42500Y115000D03*
X34900Y106742D03*
X15007Y163581D03*
X212287Y39469D03*
X202783Y128937D03*
X215400Y88900D03*
G54D19*
X22598Y150420D03*
G54D23*
X42126Y303149D03*
X202363D03*
G54D17*
X28346Y222440D03*
X188583D03*
%LPC*%
G75*
G54D27*
G01X-351984Y-328833D02*
X-383984D01*
G01X-351984Y-344833D02*
Y-424833D01*
G01D02*
X998716D01*
G01X-355984Y-328833D02*
G02I-12000J0D01*
G01X-361134D02*
G02I-6850J0D01*
G01X-367984Y-344833D02*
Y-312833D01*
G01X-351984Y-344833D02*
X998716D01*
G01X-351984Y-380333D02*
X998716D01*
G01X211216Y-344833D02*
Y-424833D01*
G01X348716Y-344833D02*
Y-424833D01*
G01X463716Y-344833D02*
Y-424833D01*
G01X631216Y-344833D02*
Y-424833D01*
G01X801216Y-344833D02*
Y-424833D01*
G01X998716Y-344833D02*
Y-424833D01*
G01X1026716Y-328833D02*
G02I-12000J0D01*
G01X1021566D02*
G02I-6850J0D01*
G01X1014716Y-344833D02*
Y-312833D01*
G01X1030716Y-328833D02*
X998716D01*
G54D28*
G01X-322688Y-405500D02*
X-321814Y-404625D01*
X-321159Y-403167D01*
X-320722Y-401124D01*
X-321159Y-399375D01*
X-322032Y-398208D01*
X-323561Y-397333D01*
X-329456D01*
Y-414833D01*
X-322251D01*
X-320722Y-413667D01*
X-319849Y-411916D01*
X-319412Y-409875D01*
X-319849Y-407833D01*
X-321159Y-406083D01*
X-322688Y-405500D01*
X-329456D01*
G01X-309991Y-414833D02*
Y-403167D01*
G01Y-405500D02*
X-308899Y-404333D01*
X-307807Y-403458D01*
X-306279Y-403167D01*
X-305188Y-403458D01*
X-303877Y-404333D01*
G01X-294019Y-420083D02*
X-292709Y-420666D01*
X-290962Y-420083D01*
X-289871Y-418917D01*
X-288997Y-417458D01*
X-287688Y-412792D01*
X-284849Y-403167D01*
G01X-291836D02*
X-287688Y-412792D01*
G01X-268441Y-404625D02*
X-269969Y-403458D01*
X-271279Y-403167D01*
X-273026Y-403750D01*
X-274336Y-404916D01*
X-275209Y-406958D01*
X-275428Y-409000D01*
X-275209Y-411042D01*
X-274336Y-412792D01*
X-273026Y-414250D01*
X-271279Y-414833D01*
X-269751Y-414250D01*
X-268441Y-413083D01*
G01X-257709Y-406958D02*
X-250722D01*
X-251377Y-404916D01*
X-252469Y-403750D01*
X-253997Y-403167D01*
X-255526Y-403458D01*
X-256836Y-404333D01*
X-257709Y-406375D01*
X-258146Y-408125D01*
Y-409875D01*
X-257709Y-411625D01*
X-256617Y-413375D01*
X-255307Y-414541D01*
X-253779Y-414833D01*
X-252251Y-414250D01*
X-250722Y-412500D01*
G01X-214631Y-398792D02*
X-215941Y-397916D01*
X-217469Y-397333D01*
X-219216D01*
X-221181Y-398208D01*
X-222709Y-399666D01*
X-223801Y-401417D01*
X-224674Y-404333D01*
X-224893Y-406958D01*
X-224456Y-409583D01*
X-223801Y-411333D01*
X-222491Y-413083D01*
X-220962Y-414250D01*
X-219434Y-414833D01*
X-217906D01*
X-216377Y-414250D01*
X-215067Y-413375D01*
X-213975Y-412209D01*
G01X-198004Y-414833D02*
Y-403167D01*
G01Y-405208D02*
X-198877Y-404042D01*
X-200188Y-403458D01*
X-201716Y-403167D01*
X-203244Y-403750D01*
X-204554Y-404916D01*
X-205428Y-406666D01*
X-205864Y-409000D01*
X-205428Y-411333D01*
X-204554Y-413083D01*
X-203244Y-414250D01*
X-201716Y-414833D01*
X-200188Y-414541D01*
X-198877Y-413667D01*
X-198004Y-412500D01*
G01X-188146Y-414833D02*
Y-403167D01*
G01Y-406083D02*
X-187272Y-404625D01*
X-185962Y-403458D01*
X-184216Y-403167D01*
X-182688Y-403458D01*
X-181377Y-404625D01*
X-180722Y-406666D01*
Y-414833D01*
G01X-171519Y-420083D02*
X-170209Y-420666D01*
X-168462Y-420083D01*
X-167371Y-418917D01*
X-166497Y-417458D01*
X-165188Y-412792D01*
X-162349Y-403167D01*
G01X-169336D02*
X-165188Y-412792D01*
G01X-149434Y-414833D02*
X-150744Y-414541D01*
X-152054Y-413375D01*
X-152928Y-411333D01*
X-153364Y-409000D01*
X-152928Y-406666D01*
X-152054Y-404625D01*
X-150744Y-403458D01*
X-149434Y-403167D01*
X-148124Y-403458D01*
X-146814Y-404625D01*
X-145941Y-406666D01*
X-145722Y-409000D01*
X-145941Y-411333D01*
X-146814Y-413375D01*
X-148124Y-414541D01*
X-149434Y-414833D01*
G01X-135646D02*
Y-403167D01*
G01Y-406083D02*
X-134772Y-404625D01*
X-133462Y-403458D01*
X-131716Y-403167D01*
X-130188Y-403458D01*
X-128877Y-404625D01*
X-128222Y-406666D01*
Y-414833D01*
G01X-101082D02*
Y-397333D01*
X-92786D01*
G01X-95842Y-405791D02*
X-101082D01*
G01X-82491Y-414833D02*
Y-403167D01*
G01Y-405500D02*
X-81399Y-404333D01*
X-80307Y-403458D01*
X-78779Y-403167D01*
X-77688Y-403458D01*
X-76377Y-404333D01*
G01X-61934Y-414833D02*
X-63244Y-414541D01*
X-64554Y-413375D01*
X-65428Y-411333D01*
X-65864Y-409000D01*
X-65428Y-406666D01*
X-64554Y-404625D01*
X-63244Y-403458D01*
X-61934Y-403167D01*
X-60624Y-403458D01*
X-59314Y-404625D01*
X-58441Y-406666D01*
X-58222Y-409000D01*
X-58441Y-411333D01*
X-59314Y-413375D01*
X-60624Y-414541D01*
X-61934Y-414833D01*
G01X-48146D02*
Y-403167D01*
G01Y-406083D02*
X-47272Y-404625D01*
X-45962Y-403458D01*
X-44216Y-403167D01*
X-42688Y-403458D01*
X-41377Y-404625D01*
X-40722Y-406666D01*
Y-414833D01*
G01X-26934Y-397333D02*
Y-414833D01*
G01X-29991Y-403167D02*
X-23877D01*
G01X3699Y-414833D02*
Y-397333D01*
X8939D01*
X10686Y-398208D01*
X11996Y-400250D01*
X12433Y-402583D01*
X11996Y-404916D01*
X10904Y-406666D01*
X8939Y-407542D01*
X3699D01*
G01X29496Y-414833D02*
Y-403167D01*
G01Y-405208D02*
X28623Y-404042D01*
X27312Y-403458D01*
X25784Y-403167D01*
X24256Y-403750D01*
X22946Y-404916D01*
X22072Y-406666D01*
X21636Y-409000D01*
X22072Y-411333D01*
X22946Y-413083D01*
X24256Y-414250D01*
X25784Y-414833D01*
X27312Y-414541D01*
X28623Y-413667D01*
X29496Y-412500D01*
G01X39354Y-414833D02*
Y-403167D01*
G01Y-406083D02*
X40228Y-404625D01*
X41538Y-403458D01*
X43284Y-403167D01*
X44812Y-403458D01*
X46123Y-404625D01*
X46778Y-406666D01*
Y-414833D01*
G01X57291Y-406958D02*
X64278D01*
X63623Y-404916D01*
X62531Y-403750D01*
X61003Y-403167D01*
X59474Y-403458D01*
X58164Y-404333D01*
X57291Y-406375D01*
X56854Y-408125D01*
Y-409875D01*
X57291Y-411625D01*
X58383Y-413375D01*
X59693Y-414541D01*
X61221Y-414833D01*
X62749Y-414250D01*
X64278Y-412500D01*
G01X78066Y-414833D02*
Y-397333D01*
G01X114812Y-405500D02*
X115686Y-404625D01*
X116341Y-403167D01*
X116778Y-401124D01*
X116341Y-399375D01*
X115468Y-398208D01*
X113939Y-397333D01*
X108044D01*
Y-414833D01*
X115249D01*
X116778Y-413667D01*
X117651Y-411916D01*
X118088Y-409875D01*
X117651Y-407833D01*
X116341Y-406083D01*
X114812Y-405500D01*
X108044D01*
G01X130566Y-414833D02*
X129256Y-414541D01*
X127946Y-413375D01*
X127072Y-411333D01*
X126636Y-409000D01*
X127072Y-406666D01*
X127946Y-404625D01*
X129256Y-403458D01*
X130566Y-403167D01*
X131876Y-403458D01*
X133186Y-404625D01*
X134059Y-406666D01*
X134278Y-409000D01*
X134059Y-411333D01*
X133186Y-413375D01*
X131876Y-414541D01*
X130566Y-414833D01*
G01X151996D02*
Y-403167D01*
G01Y-405208D02*
X151123Y-404042D01*
X149812Y-403458D01*
X148284Y-403167D01*
X146756Y-403750D01*
X145446Y-404916D01*
X144572Y-406666D01*
X144136Y-409000D01*
X144572Y-411333D01*
X145446Y-413083D01*
X146756Y-414250D01*
X148284Y-414833D01*
X149812Y-414541D01*
X151123Y-413667D01*
X151996Y-412500D01*
G01X162509Y-414833D02*
Y-403167D01*
G01Y-405500D02*
X163601Y-404333D01*
X164693Y-403458D01*
X166221Y-403167D01*
X167312Y-403458D01*
X168623Y-404333D01*
G01X186996Y-397333D02*
Y-414833D01*
G01Y-412209D02*
X186123Y-413667D01*
X184812Y-414541D01*
X183284Y-414833D01*
X181538Y-414250D01*
X180228Y-412792D01*
X179354Y-411042D01*
X179136Y-409000D01*
X179354Y-406958D01*
X180228Y-405208D01*
X181538Y-403750D01*
X183284Y-403167D01*
X184812Y-403458D01*
X185904Y-404042D01*
X186996Y-405208D01*
G01X-111361Y-369833D02*
Y-352333D01*
X-105684Y-366916D01*
X-100007Y-352333D01*
Y-369833D01*
G01X-88184D02*
X-89494Y-369541D01*
X-90804Y-368375D01*
X-91678Y-366333D01*
X-92114Y-364000D01*
X-91678Y-361666D01*
X-90804Y-359625D01*
X-89494Y-358458D01*
X-88184Y-358167D01*
X-86874Y-358458D01*
X-85564Y-359625D01*
X-84691Y-361666D01*
X-84472Y-364000D01*
X-84691Y-366333D01*
X-85564Y-368375D01*
X-86874Y-369541D01*
X-88184Y-369833D01*
G01X-66754Y-352333D02*
Y-369833D01*
G01Y-367209D02*
X-67627Y-368667D01*
X-68938Y-369541D01*
X-70466Y-369833D01*
X-72212Y-369250D01*
X-73522Y-367792D01*
X-74396Y-366042D01*
X-74614Y-364000D01*
X-74396Y-361958D01*
X-73522Y-360208D01*
X-72212Y-358750D01*
X-70466Y-358167D01*
X-68938Y-358458D01*
X-67846Y-359042D01*
X-66754Y-360208D01*
G01X-56459Y-361958D02*
X-49472D01*
X-50127Y-359916D01*
X-51219Y-358750D01*
X-52747Y-358167D01*
X-54276Y-358458D01*
X-55586Y-359333D01*
X-56459Y-361375D01*
X-56896Y-363125D01*
Y-364875D01*
X-56459Y-366625D01*
X-55367Y-368375D01*
X-54057Y-369541D01*
X-52529Y-369833D01*
X-51001Y-369250D01*
X-49472Y-367500D01*
G01X-35684Y-369833D02*
Y-352333D01*
G01X244916Y-414833D02*
Y-397333D01*
X242296Y-400833D01*
G01Y-414833D02*
X247536D01*
G01X258268Y-407542D02*
X259796Y-405500D01*
X261106Y-404333D01*
X262853Y-403750D01*
X264381Y-404333D01*
X265473Y-405500D01*
X266346Y-407250D01*
X266564Y-409291D01*
X266346Y-411042D01*
X265473Y-412792D01*
X264162Y-414250D01*
X262634Y-414833D01*
X260888Y-414250D01*
X259359Y-412500D01*
X258486Y-409875D01*
X258268Y-406958D01*
X258704Y-403167D01*
X259359Y-401124D01*
X260451Y-399083D01*
X261979Y-397625D01*
X263508Y-397333D01*
X265036Y-397916D01*
X266128Y-399375D01*
G01X275113Y-411333D02*
X276422Y-413375D01*
X278169Y-414541D01*
X280134Y-414833D01*
X281881Y-414541D01*
X283628Y-413083D01*
X284719Y-411333D01*
X284938Y-409583D01*
X284501Y-407542D01*
X282973Y-406083D01*
X281444Y-405500D01*
X279479D01*
G01X281444D02*
X282754Y-404625D01*
X283846Y-403167D01*
X284283Y-401417D01*
X283846Y-399666D01*
X282754Y-398208D01*
X280789Y-397333D01*
X278824Y-397625D01*
X276859Y-398792D01*
G01X293268Y-407542D02*
X294796Y-405500D01*
X296106Y-404333D01*
X297853Y-403750D01*
X299381Y-404333D01*
X300473Y-405500D01*
X301346Y-407250D01*
X301564Y-409291D01*
X301346Y-411042D01*
X300473Y-412792D01*
X299162Y-414250D01*
X297634Y-414833D01*
X295888Y-414250D01*
X294359Y-412500D01*
X293486Y-409875D01*
X293268Y-406958D01*
X293704Y-403167D01*
X294359Y-401124D01*
X295451Y-399083D01*
X296979Y-397625D01*
X298508Y-397333D01*
X300036Y-397916D01*
X301128Y-399375D01*
G01X311204Y-412792D02*
X312733Y-414250D01*
X314479Y-414833D01*
X316226Y-414250D01*
X317754Y-412500D01*
X318846Y-409875D01*
X319283Y-407250D01*
Y-404042D01*
X318846Y-401417D01*
X317754Y-399083D01*
X316444Y-397916D01*
X314916Y-397333D01*
X313169Y-397916D01*
X311859Y-399083D01*
X310986Y-400833D01*
X310549Y-403167D01*
X310986Y-405208D01*
X312078Y-407250D01*
X313388Y-408417D01*
X314916Y-408708D01*
X316662Y-408125D01*
X317973Y-406666D01*
X319283Y-404042D01*
G01X231799Y-369833D02*
Y-352333D01*
X237039D01*
X238786Y-353208D01*
X240096Y-355250D01*
X240533Y-357583D01*
X240096Y-359916D01*
X239004Y-361666D01*
X237039Y-362542D01*
X231799D01*
G01X258469Y-353792D02*
X257159Y-352916D01*
X255631Y-352333D01*
X253884D01*
X251919Y-353208D01*
X250391Y-354666D01*
X249299Y-356417D01*
X248426Y-359333D01*
X248207Y-361958D01*
X248644Y-364583D01*
X249299Y-366333D01*
X250609Y-368083D01*
X252138Y-369250D01*
X253666Y-369833D01*
X255194D01*
X256723Y-369250D01*
X258033Y-368375D01*
X259125Y-367209D01*
G01X272912Y-360500D02*
X273786Y-359625D01*
X274441Y-358167D01*
X274878Y-356124D01*
X274441Y-354375D01*
X273568Y-353208D01*
X272039Y-352333D01*
X266144D01*
Y-369833D01*
X273349D01*
X274878Y-368667D01*
X275751Y-366916D01*
X276188Y-364875D01*
X275751Y-362833D01*
X274441Y-361083D01*
X272912Y-360500D01*
X266144D01*
G01X282116Y-375666D02*
X295216D01*
G01X301144Y-369833D02*
Y-352333D01*
X311188Y-369833D01*
Y-352333D01*
G01X323666Y-369833D02*
X321919Y-369541D01*
X320391Y-368375D01*
X319081Y-366625D01*
X318207Y-364583D01*
X317771Y-362250D01*
Y-359916D01*
X318207Y-357583D01*
X319081Y-355541D01*
X320391Y-353792D01*
X321919Y-352625D01*
X323666Y-352333D01*
X325412Y-352625D01*
X326941Y-353792D01*
X328251Y-355541D01*
X329125Y-357583D01*
X329561Y-359916D01*
Y-362250D01*
X329125Y-364583D01*
X328251Y-366625D01*
X326941Y-368375D01*
X325412Y-369541D01*
X323666Y-369833D01*
G01X374507Y-352333D02*
X379966Y-369833D01*
X385425Y-352333D01*
G01X401833Y-369833D02*
X393099D01*
Y-352333D01*
X401833D01*
G01X398339Y-360791D02*
X393099D01*
G01X410599Y-369833D02*
Y-352333D01*
X416058D01*
X417804Y-353208D01*
X418896Y-354375D01*
X419333Y-356708D01*
X418896Y-359042D01*
X417586Y-360500D01*
X416058Y-361375D01*
X410599D01*
G01X416058D02*
X419333Y-369833D01*
G01X432466Y-370416D02*
X432029Y-370125D01*
Y-369541D01*
X432466Y-369250D01*
X432903Y-369541D01*
Y-370125D01*
X432466Y-370416D01*
G01X392881Y-412500D02*
X394628Y-413958D01*
X396593Y-414833D01*
X398339D01*
X400086Y-413958D01*
X401396Y-412500D01*
X402051Y-410458D01*
X401614Y-408417D01*
X400523Y-406666D01*
X398558Y-405500D01*
X395938Y-404916D01*
X394409Y-403750D01*
X393754Y-401708D01*
X394191Y-399666D01*
X395283Y-398208D01*
X396811Y-397333D01*
X398339D01*
X399868Y-397916D01*
X401178Y-399375D01*
G01X410163Y-414833D02*
Y-397333D01*
X414529D01*
X416276Y-398208D01*
X417586Y-399375D01*
X418678Y-401124D01*
X419551Y-403167D01*
X419769Y-406083D01*
X419551Y-409000D01*
X418678Y-411042D01*
X417586Y-412792D01*
X416276Y-413958D01*
X414529Y-414833D01*
X410163D01*
G01X508049Y-397333D02*
Y-414833D01*
X516783D01*
G01X525768Y-400250D02*
X527078Y-398500D01*
X528606Y-397625D01*
X530353Y-397333D01*
X532536Y-397916D01*
X534064Y-399375D01*
X534501Y-401124D01*
X534283Y-402875D01*
X533409Y-404333D01*
X529043Y-407250D01*
X527078Y-409291D01*
X525768Y-412209D01*
X525331Y-414833D01*
X534501D01*
G01X548726Y-406083D02*
X553093D01*
Y-411333D01*
X551783Y-413083D01*
X550254Y-414250D01*
X548071Y-414833D01*
X545888Y-414250D01*
X544359Y-413083D01*
X543049Y-411333D01*
X542176Y-409291D01*
X541739Y-406958D01*
Y-404916D01*
X542176Y-403167D01*
X543049Y-401124D01*
X544359Y-399375D01*
X545669Y-398208D01*
X547416Y-397333D01*
X548944D01*
X550691Y-397916D01*
X552001Y-399083D01*
G01X559894Y-414833D02*
Y-397333D01*
X569938Y-414833D01*
Y-397333D01*
G01X577613Y-414833D02*
Y-397333D01*
X581979D01*
X583726Y-398208D01*
X585036Y-399375D01*
X586128Y-401124D01*
X587001Y-403167D01*
X587219Y-406083D01*
X587001Y-409000D01*
X586128Y-411042D01*
X585036Y-412792D01*
X583726Y-413958D01*
X581979Y-414833D01*
X577613D01*
G01X508049Y-352333D02*
Y-369833D01*
X516783D01*
G01X533846D02*
Y-358167D01*
G01Y-360208D02*
X532973Y-359042D01*
X531662Y-358458D01*
X530134Y-358167D01*
X528606Y-358750D01*
X527296Y-359916D01*
X526422Y-361666D01*
X525986Y-364000D01*
X526422Y-366333D01*
X527296Y-368083D01*
X528606Y-369250D01*
X530134Y-369833D01*
X531662Y-369541D01*
X532973Y-368667D01*
X533846Y-367500D01*
G01X542831Y-375083D02*
X544141Y-375666D01*
X545888Y-375083D01*
X546979Y-373917D01*
X547853Y-372458D01*
X549162Y-367792D01*
X552001Y-358167D01*
G01X545014D02*
X549162Y-367792D01*
G01X561641Y-361958D02*
X568628D01*
X567973Y-359916D01*
X566881Y-358750D01*
X565353Y-358167D01*
X563824Y-358458D01*
X562514Y-359333D01*
X561641Y-361375D01*
X561204Y-363125D01*
Y-364875D01*
X561641Y-366625D01*
X562733Y-368375D01*
X564043Y-369541D01*
X565571Y-369833D01*
X567099Y-369250D01*
X568628Y-367500D01*
G01X579359Y-369833D02*
Y-358167D01*
G01Y-360500D02*
X580451Y-359333D01*
X581543Y-358458D01*
X583071Y-358167D01*
X584162Y-358458D01*
X585473Y-359333D01*
G01X672466Y-414833D02*
X670719Y-414541D01*
X669191Y-413375D01*
X667881Y-411625D01*
X667007Y-409583D01*
X666571Y-407250D01*
Y-404916D01*
X667007Y-402583D01*
X667881Y-400541D01*
X669191Y-398792D01*
X670719Y-397625D01*
X672466Y-397333D01*
X674212Y-397625D01*
X675741Y-398792D01*
X677051Y-400541D01*
X677925Y-402583D01*
X678361Y-404916D01*
Y-407250D01*
X677925Y-409583D01*
X677051Y-411625D01*
X675741Y-413375D01*
X674212Y-414541D01*
X672466Y-414833D01*
G01X674212Y-410166D02*
X676833Y-414833D01*
G01X685163Y-397333D02*
Y-409875D01*
X686036Y-412500D01*
X687783Y-414250D01*
X689966Y-414833D01*
X692149Y-414250D01*
X693896Y-412500D01*
X694769Y-409875D01*
Y-397333D01*
G01X704846D02*
X710086D01*
G01X707466D02*
Y-414833D01*
G01X704846D02*
X710086D01*
G01X719944D02*
Y-397333D01*
X729988Y-414833D01*
Y-397333D01*
G01X747269Y-398792D02*
X745959Y-397916D01*
X744431Y-397333D01*
X742684D01*
X740719Y-398208D01*
X739191Y-399666D01*
X738099Y-401417D01*
X737226Y-404333D01*
X737007Y-406958D01*
X737444Y-409583D01*
X738099Y-411333D01*
X739409Y-413083D01*
X740938Y-414250D01*
X742466Y-414833D01*
X743994D01*
X745523Y-414250D01*
X746833Y-413375D01*
X747925Y-412209D01*
G01X759966Y-414833D02*
Y-406958D01*
X755599Y-397333D01*
G01X764333D02*
X759966Y-406958D01*
G01X650163Y-369833D02*
Y-352333D01*
X654529D01*
X656276Y-353208D01*
X657586Y-354375D01*
X658678Y-356124D01*
X659551Y-358167D01*
X659769Y-361083D01*
X659551Y-364000D01*
X658678Y-366042D01*
X657586Y-367792D01*
X656276Y-368958D01*
X654529Y-369833D01*
X650163D01*
G01X669191Y-361958D02*
X676178D01*
X675523Y-359916D01*
X674431Y-358750D01*
X672903Y-358167D01*
X671374Y-358458D01*
X670064Y-359333D01*
X669191Y-361375D01*
X668754Y-363125D01*
Y-364875D01*
X669191Y-366625D01*
X670283Y-368375D01*
X671593Y-369541D01*
X673121Y-369833D01*
X674649Y-369250D01*
X676178Y-367500D01*
G01X686691Y-367792D02*
X687783Y-368958D01*
X689311Y-369833D01*
X690621D01*
X691931Y-369250D01*
X692804Y-368375D01*
X693241Y-367209D01*
X693023Y-365458D01*
X692149Y-364583D01*
X688219Y-362833D01*
X687346Y-360791D01*
X687783Y-359333D01*
X688656Y-358458D01*
X689966Y-358167D01*
X691276Y-358458D01*
X692586Y-359333D01*
G01X707466Y-358167D02*
Y-369833D01*
G01Y-353500D02*
X707029Y-353208D01*
Y-352625D01*
X707466Y-352333D01*
X707903Y-352625D01*
Y-353208D01*
X707466Y-353500D01*
G01X721909Y-374208D02*
X723438Y-375375D01*
X725184Y-375666D01*
X726712Y-375375D01*
X728023Y-373917D01*
X728896Y-371875D01*
Y-358167D01*
G01Y-360500D02*
X728023Y-359333D01*
X726712Y-358458D01*
X725184Y-358167D01*
X723438Y-358750D01*
X722346Y-359916D01*
X721472Y-361958D01*
X721036Y-364000D01*
X721254Y-365750D01*
X722128Y-367792D01*
X723438Y-369250D01*
X725184Y-369833D01*
X726494Y-369541D01*
X728023Y-368375D01*
X728896Y-367209D01*
G01X738754Y-369833D02*
Y-358167D01*
G01Y-361083D02*
X739628Y-359625D01*
X740938Y-358458D01*
X742684Y-358167D01*
X744212Y-358458D01*
X745523Y-359625D01*
X746178Y-361666D01*
Y-369833D01*
G01X756691Y-361958D02*
X763678D01*
X763023Y-359916D01*
X761931Y-358750D01*
X760403Y-358167D01*
X758874Y-358458D01*
X757564Y-359333D01*
X756691Y-361375D01*
X756254Y-363125D01*
Y-364875D01*
X756691Y-366625D01*
X757783Y-368375D01*
X759093Y-369541D01*
X760621Y-369833D01*
X762149Y-369250D01*
X763678Y-367500D01*
G01X774409Y-369833D02*
Y-358167D01*
G01Y-360500D02*
X775501Y-359333D01*
X776593Y-358458D01*
X778121Y-358167D01*
X779212Y-358458D01*
X780523Y-359333D01*
G01X821166Y-397333D02*
X819419Y-397916D01*
X818109Y-399375D01*
X817236Y-401124D01*
X816581Y-403458D01*
X816363Y-406083D01*
X816581Y-408708D01*
X817236Y-411042D01*
X818109Y-412792D01*
X819419Y-414250D01*
X821166Y-414833D01*
X822912Y-414250D01*
X824223Y-412792D01*
X825096Y-411042D01*
X825751Y-408708D01*
X825969Y-406083D01*
X825751Y-403458D01*
X825096Y-401124D01*
X824223Y-399375D01*
X822912Y-397916D01*
X821166Y-397333D01*
G01X833863Y-411333D02*
X835172Y-413375D01*
X836919Y-414541D01*
X838884Y-414833D01*
X840631Y-414541D01*
X842378Y-413083D01*
X843469Y-411333D01*
X843688Y-409583D01*
X843251Y-407542D01*
X841723Y-406083D01*
X840194Y-405500D01*
X838229D01*
G01X840194D02*
X841504Y-404625D01*
X842596Y-403167D01*
X843033Y-401417D01*
X842596Y-399666D01*
X841504Y-398208D01*
X839539Y-397333D01*
X837574Y-397625D01*
X835609Y-398792D01*
G01X852236Y-415416D02*
X860096Y-397333D01*
G01X869518Y-400250D02*
X870828Y-398500D01*
X872356Y-397625D01*
X874103Y-397333D01*
X876286Y-397916D01*
X877814Y-399375D01*
X878251Y-401124D01*
X878033Y-402875D01*
X877159Y-404333D01*
X872793Y-407250D01*
X870828Y-409291D01*
X869518Y-412209D01*
X869081Y-414833D01*
X878251D01*
G01X887454Y-412792D02*
X888983Y-414250D01*
X890729Y-414833D01*
X892476Y-414250D01*
X894004Y-412500D01*
X895096Y-409875D01*
X895533Y-407250D01*
Y-404042D01*
X895096Y-401417D01*
X894004Y-399083D01*
X892694Y-397916D01*
X891166Y-397333D01*
X889419Y-397916D01*
X888109Y-399083D01*
X887236Y-400833D01*
X886799Y-403167D01*
X887236Y-405208D01*
X888328Y-407250D01*
X889638Y-408417D01*
X891166Y-408708D01*
X892912Y-408125D01*
X894223Y-406666D01*
X895533Y-404042D01*
G01X904736Y-415416D02*
X912596Y-397333D01*
G01X922018Y-400250D02*
X923328Y-398500D01*
X924856Y-397625D01*
X926603Y-397333D01*
X928786Y-397916D01*
X930314Y-399375D01*
X930751Y-401124D01*
X930533Y-402875D01*
X929659Y-404333D01*
X925293Y-407250D01*
X923328Y-409291D01*
X922018Y-412209D01*
X921581Y-414833D01*
X930751D01*
G01X943666Y-397333D02*
X941919Y-397916D01*
X940609Y-399375D01*
X939736Y-401124D01*
X939081Y-403458D01*
X938863Y-406083D01*
X939081Y-408708D01*
X939736Y-411042D01*
X940609Y-412792D01*
X941919Y-414250D01*
X943666Y-414833D01*
X945412Y-414250D01*
X946723Y-412792D01*
X947596Y-411042D01*
X948251Y-408708D01*
X948469Y-406083D01*
X948251Y-403458D01*
X947596Y-401124D01*
X946723Y-399375D01*
X945412Y-397916D01*
X943666Y-397333D01*
G01X961166Y-414833D02*
Y-397333D01*
X958546Y-400833D01*
G01Y-414833D02*
X963786D01*
G01X978229D02*
X978666Y-411042D01*
X979321Y-407833D01*
X980194Y-404916D01*
X981286Y-401708D01*
X983033Y-397333D01*
X974299D01*
G01X868863Y-369833D02*
Y-352333D01*
X873229D01*
X874976Y-353208D01*
X876286Y-354375D01*
X877378Y-356124D01*
X878251Y-358167D01*
X878469Y-361083D01*
X878251Y-364000D01*
X877378Y-366042D01*
X876286Y-367792D01*
X874976Y-368958D01*
X873229Y-369833D01*
X868863D01*
G01X895096D02*
Y-358167D01*
G01Y-360208D02*
X894223Y-359042D01*
X892912Y-358458D01*
X891384Y-358167D01*
X889856Y-358750D01*
X888546Y-359916D01*
X887672Y-361666D01*
X887236Y-364000D01*
X887672Y-366333D01*
X888546Y-368083D01*
X889856Y-369250D01*
X891384Y-369833D01*
X892912Y-369541D01*
X894223Y-368667D01*
X895096Y-367500D01*
G01X908666Y-352333D02*
Y-369833D01*
G01X905609Y-358167D02*
X911723D01*
G01X922891Y-361958D02*
X929878D01*
X929223Y-359916D01*
X928131Y-358750D01*
X926603Y-358167D01*
X925074Y-358458D01*
X923764Y-359333D01*
X922891Y-361375D01*
X922454Y-363125D01*
Y-364875D01*
X922891Y-366625D01*
X923983Y-368375D01*
X925293Y-369541D01*
X926821Y-369833D01*
X928349Y-369250D01*
X929878Y-367500D01*
M02*
